FILE_TYPE = CONNECTIVITY;
{Allegro Design Entry HDL 17.4-2019 S026 (4007227) 1/17/2022}
"PAGE_NUMBER" = 319;
0"NC";
1"PRSNT_CABLE_GPU_B3_N";
2"P5E_CPU1_P2_RX_BUF_DN<15>";
3"P5E_CPU1_P2_RX_BUF_DP<15>";
4"P5E_CPU1_P3_TX_BUF_C_DP<15>";
5"P5E_CPU1_P3_TX_BUF_C_DN<15>";
6"P5E_CPU1_P2_TX_BUF_C_DP<15>";
7"P5E_CPU1_P2_TX_BUF_C_DN<15>";
8"SMB_BMC_SWB_BUF_SDA";
9"P5E_CPU1_P2_RX_BUF_DP<14>";
10"P5E_CPU1_P3_TX_BUF_C_DP<14>";
11"P5E_CPU1_P3_RX_BUF_DN<13>";
12"P5E_CPU1_P3_TX_BUF_C_DN<8>";
13"P5E_CPU1_P3_TX_BUF_C_DP<8>";
14"GND\g";
15"P5E_CPU1_P2_TX_BUF_C_DP<8>";
16"P5E_CPU1_P3_RX_BUF_DP<8>";
17"P5E_CPU1_P3_RX_BUF_DN<8>";
18"P5E_CPU1_P2_RX_BUF_DP<8>";
19"BMC_MONITER_BUF";
20"P5E_CPU1_P3_TX_BUF_C_DP<9>";
21"GPU_FPGA_EROT_FATALERR_N";
22"P5E_CPU1_P2_RX_BUF_DN<8>";
23"P5E_CPU1_P3_TX_BUF_C_DN<9>";
24"P5E_CPU1_P2_TX_BUF_C_DP<9>";
25"P5E_CPU1_P2_TX_BUF_C_DN<9>";
26"P5E_CPU1_P2_RX_BUF_DP<9>";
27"P5E_CPU1_P3_TX_BUF_C_DP<10>";
28"P5E_CPU1_P3_TX_BUF_C_DN<10>";
29"P5E_CPU1_P2_RX_BUF_DN<9>";
30"P5E_CPU1_P2_TX_BUF_C_DP<10>";
31"P5E_CPU1_P3_RX_BUF_DP<10>";
32"P5E_CPU1_P2_RX_BUF_DP<10>";
33"BIC_MONITER";
34"GPU_3V3IO_RSVD0_FFU";
35"P5E_CPU1_P3_TX_BUF_C_DP<11>";
36"P5E_CPU1_P3_TX_BUF_C_DN<11>";
37"P5E_CPU1_P2_TX_BUF_C_DP<11>";
38"P5E_CPU1_P2_TX_BUF_C_DN<11>";
39"P5E_CPU1_P3_RX_BUF_DP<11>";
40"P5E_CPU1_P3_RX_BUF_DN<11>";
41"P5E_CPU1_P2_RX_BUF_DP<11>";
42"P5E_CPU1_P2_RX_BUF_DN<11>";
43"SMB_BMC_SWB_BUF_SCL";
44"GND\g";
45"P5E_CPU1_P2_RX_BUF_DN<12>";
46"P5E_CPU1_P2_RX_BUF_DP<12>";
47"GPU_3V3IO_RSVD1_FFU";
48"P5E_CPU1_P3_TX_BUF_C_DN<13>";
49"P5E_CPU1_P3_TX_BUF_C_DP<13>";
50"P5E_CPU1_P3_RX_BUF_DP<12>";
51"P5E_CPU1_P2_TX_BUF_C_DN<12>";
52"P5E_CPU1_P2_TX_BUF_C_DP<12>";
53"P5E_CPU1_P3_TX_BUF_C_DP<12>";
54"P5E_CPU1_P3_RX_BUF_DN<12>";
55"P5E_CPU1_P2_TX_BUF_C_DP<13>";
56"P5E_CPU1_P2_TX_BUF_C_DN<13>";
57"P5E_CPU1_P3_RX_BUF_DP<13>";
58"P5E_CPU1_P2_RX_BUF_DP<13>";
59"P5E_CPU1_P3_TX_BUF_C_DN<14>";
60"P5E_CPU1_P2_TX_BUF_C_DP<14>";
61"P5E_CPU1_P2_TX_BUF_C_DN<14>";
62"P5E_CPU1_P3_RX_BUF_DP<14>";
63"P5E_CPU1_P3_RX_BUF_DN<14>";
64"P5E_CPU1_P3_TX_BUF_C_DN<12>";
65"P5E_CPU1_P2_RX_BUF_DN<13>";
66"P5E_CPU1_P3_RX_BUF_DP<15>";
67"P5E_CPU1_P2_RX_BUF_DN<14>";
68"P5E_CPU1_P2_TX_BUF_C_DN<8>";
69"P5E_CPU1_P3_RX_BUF_DP<9>";
70"P5E_CPU1_P3_RX_BUF_DN<10>";
71"P5E_CPU1_P3_RX_BUF_DN<15>";
72"P5E_CPU1_P2_TX_BUF_C_DN<10>";
73"P5E_CPU1_P2_RX_BUF_DN<10>";
74"P5E_CPU1_P3_RX_BUF_DN<9>";
%"UNIVERSAL_GND"
"1","(-2225,-1125)","0","pure_quanta_power","I15";
;
CDS_LIB"pure_quanta_power"
HDL_POWER"GND";
"A"44;
%"CONN112_10137002101LF"
"1","(-1125,775)","0","pure_quanta","I16";
;
LOCATION"J109"
$SEC"1"
CDS_SEC"1"
MATERIAL"IO"
PART_TYPE"THLF"
VALUE"CONN112_10137002-101LF"
NEEDS_NO_SIZE"TRUE"
CDS_LMAN_SYM_OUTLINE"-775,1650,775,-1650"
CDS_LIB"pure_quanta"
PART_NUMBER"DFHSB2FR012";
"N8"
$PN"N8"1;
"M8"
$PN"M8"44;
"N7"
$PN"N7"44;
"M7"
$PN"M7"10;
"N6"
$PN"N6"47;
"M6"
$PN"M6"44;
"N5"
$PN"N5"44;
"M5"
$PN"M5"53;
"L5"
$PN"L5"64;
"L6"
$PN"L6"49;
"L7"
$PN"L7"59;
"L8"
$PN"L8"4;
"K5"
$PN"K5"44;
"K6"
$PN"K6"48;
"K7"
$PN"K7"44;
"K8"
$PN"K8"5;
"J5"
$PN"J5"52;
"J6"
$PN"J6"44;
"J7"
$PN"J7"60;
"J8"
$PN"J8"44;
"I5"
$PN"I5"51;
"I6"
$PN"I6"55;
"I7"
$PN"I7"61;
"I8"
$PN"I8"6;
"H5"
$PN"H5"44;
"H6"
$PN"H6"56;
"H7"
$PN"H7"44;
"H8"
$PN"H8"7;
"G5"
$PN"G5"50;
"G6"
$PN"G6"44;
"G7"
$PN"G7"62;
"G8"
$PN"G8"44;
"F5"
$PN"F5"54;
"F6"
$PN"F6"57;
"F7"
$PN"F7"63;
"F8"
$PN"F8"66;
"E5"
$PN"E5"44;
"E6"
$PN"E6"11;
"E7"
$PN"E7"44;
"E8"
$PN"E8"71;
"D5"
$PN"D5"46;
"D6"
$PN"D6"44;
"D7"
$PN"D7"9;
"D8"
$PN"D8"44;
"C5"
$PN"C5"45;
"C6"
$PN"C6"58;
"C7"
$PN"C7"67;
"C8"
$PN"C8"3;
"B5"
$PN"B5"44;
"B6"
$PN"B6"65;
"B7"
$PN"B7"44;
"B8"
$PN"B8"2;
"A5"
$PN"A5"43;
"A6"
$PN"A6"44;
"A7"
$PN"A7"8;
"A8"
$PN"A8"44;
%"UNIVERSAL_GND"
"1","(2500,-1250)","0","pure_quanta_power","I54";
;
CDS_LIB"pure_quanta_power"
HDL_POWER"GND";
"A"14;
%"CONN112_10137002101LF"
"2","(3650,700)","0","pure_quanta","I76";
;
LOCATION"J109"
$SEC"2"
CDS_SEC"2"
PART_TYPE"THLF"
MATERIAL"IO"
CDS_LIB"pure_quanta"
CDS_LMAN_SYM_OUTLINE"-775,1650,775,-1650"
VALUE"CONN112_10137002-101LF"
NEEDS_NO_SIZE"TRUE"
PART_NUMBER"DFHSB2FR012";
"N4"
$PN"N4"34;
"M4"
$PN"M4"14;
"N3"
$PN"N3"14;
"M3"
$PN"M3"27;
"N2"
$PN"N2"21;
"M2"
$PN"M2"14;
"N1"
$PN"N1"14;
"M1"
$PN"M1"13;
"L1"
$PN"L1"12;
"L2"
$PN"L2"20;
"L3"
$PN"L3"28;
"L4"
$PN"L4"35;
"K1"
$PN"K1"14;
"K2"
$PN"K2"23;
"K3"
$PN"K3"14;
"K4"
$PN"K4"36;
"J1"
$PN"J1"15;
"J2"
$PN"J2"14;
"J3"
$PN"J3"30;
"J4"
$PN"J4"14;
"I1"
$PN"I1"68;
"I2"
$PN"I2"24;
"I3"
$PN"I3"72;
"I4"
$PN"I4"37;
"H1"
$PN"H1"14;
"H2"
$PN"H2"25;
"H3"
$PN"H3"14;
"H4"
$PN"H4"38;
"G1"
$PN"G1"16;
"G2"
$PN"G2"14;
"G3"
$PN"G3"31;
"G4"
$PN"G4"14;
"F1"
$PN"F1"17;
"F2"
$PN"F2"69;
"F3"
$PN"F3"70;
"F4"
$PN"F4"39;
"E1"
$PN"E1"14;
"E2"
$PN"E2"74;
"E3"
$PN"E3"14;
"E4"
$PN"E4"40;
"D1"
$PN"D1"18;
"D2"
$PN"D2"14;
"D3"
$PN"D3"32;
"D4"
$PN"D4"14;
"C1"
$PN"C1"22;
"C2"
$PN"C2"26;
"C3"
$PN"C3"73;
"C4"
$PN"C4"41;
"B1"
$PN"B1"14;
"B2"
$PN"B2"29;
"B3"
$PN"B3"14;
"B4"
$PN"B4"42;
"A1"
$PN"A1"19;
"A2"
$PN"A2"14;
"A3"
$PN"A3"33;
"A4"
$PN"A4"14;
END.
